# T6G (Grand Teton) — schematic parts with pin connectivity, parts 6087–6232 of 8303; source: Cadence DE-HDL packaged netlist (pstxprt.dat, pstxnet.dat, pstchip.dat)

R1363  Q_RES  33 5% CHIP  pkg 0402LF  page 259 : 1 = PWRGD_P12V_MEM ; 2 = PWRGD_P12V_MEM_R
R1364  Q_RES  1K 1% CHIP  pkg 0201LF  page 276 : 1 = JTAG_TRST_RT_CPU0_P0_N ; 2 = GND
R1365  Q_RES  4.7K 5% CHIP  pkg 0201LF  page 276 : 1 = JTAG_TCK_RT_CPU0_P0 ; 2 = GND
R1366  Q_RES  4.7K 5% CHIP  pkg 0201LF  page 185 : 1 = P1V8_CPU0_RT_1D ; 2 = SMB_RT_CPU0_P0_ROM_MUX_2D_R_SDA
R1367  Q_RES  4.7K 5% CHIP  pkg 0201LF  page 185 : 1 = P1V8_CPU0_RT_1D ; 2 = SMB_RT_CPU0_P0_ROM_MUX_2D_R_SCL
R1368  Q_RES  4.7K 5% CHIP  pkg 0201LF  page 276 : 1 = CLKREQ_RT_CPU0_P0_N ; 2 = GND
R1369  Q_RES  1K 1% EMPTY  pkg 0201LF  page 276 : 1 = P1V8_CPU0_RT_1D ; 2 = RXDET_BYP_RT_CPU0_P0
R1370  Q_RES  10K 1% CHIP  pkg 0201LF  page 276 : 1 = RXDET_BYP_RT_CPU0_P0 ; 2 = GND
R1371  Q_RES  4.7K 5% CHIP  pkg 0201LF  page 185 : 1 = P1V8_CPU0_RT_1D ; 2 = SMB_RT_CPU0_P1_ROM_MUX_2D_R_SDA
R1372  Q_RES  1K 1% CHIP  pkg 0201LF  page 331 : 1 = JTAG_TRST_RT_CPU1_P1_N ; 2 = GND
R1373  Q_RES  4.7K 5% CHIP  pkg 0201LF  page 331 : 1 = JTAG_TCK_RT_CPU1_P1 ; 2 = GND
R1374  Q_RES  4.7K 5% CHIP  pkg 0201LF  page 185 : 1 = P1V8_CPU0_RT_1D ; 2 = SMB_RT_CPU0_P1_ROM_MUX_2D_R_SCL
R1375  Q_RES  4.7K 5% CHIP  pkg 0201LF  page 185 : 1 = P1V8_CPU0_RT_1D ; 2 = SMB_RT_CPU0_P3_ROM_MUX_2D_R_SDA
R1376  Q_RES  4.7K 5% CHIP  pkg 0201LF  page 331 : 1 = CLKREQ_RT_CPU1_P1_N ; 2 = GND
R1377  Q_RES  1K 1% EMPTY  pkg 0201LF  page 331 : 1 = P1V8_CPU1_RT_1D ; 2 = RXDET_BYP_RT_CPU1_P1
R1378  Q_RES  10K 1% CHIP  pkg 0201LF  page 331 : 1 = RXDET_BYP_RT_CPU1_P1 ; 2 = GND
R1379  Q_RES  4.7K 5% CHIP  pkg 0201LF  page 185 : 1 = P1V8_CPU0_RT_1D ; 2 = SMB_RT_CPU0_P3_ROM_MUX_2D_R_SCL
R1380  Q_RES  1K 1% CHIP  pkg 0201LF  page 320 : 1 = JTAG_TRST_RT_CPU1_P0_N ; 2 = GND
R1381  Q_RES  4.7K 5% CHIP  pkg 0201LF  page 320 : 1 = JTAG_TCK_RT_CPU1_P0 ; 2 = GND
R1382  Q_RES  4.7K 5% CHIP  pkg 0201LF  page 185 : 1 = P1V8_CPU0_RT_1D ; 2 = SMB_RT_CPU0_P2_ROM_MUX_2D_R_SDA
R1383  Q_RES  4.7K 5% CHIP  pkg 0201LF  page 185 : 1 = P1V8_CPU0_RT_1D ; 2 = SMB_RT_CPU0_P2_ROM_MUX_2D_R_SCL
R1384  Q_RES  2K 1% EMPTY  pkg 0402LF  page 151 : 1 = SMB_CPU0_CPU1_SEC_SCL ; 2 = P3V3_AUX
R1385  Q_RES  2K 1% EMPTY  pkg 0402LF  page 151 : 1 = SMB_CPU0_CPU1_SEC_SDA ; 2 = P3V3_AUX
R1386  Q_RES  2K 1% EMPTY  pkg 0402LF  page 151 : 1 = SMB_PMBUS_3V3AUX_SCL ; 2 = P3V3_AUX
R1387  Q_RES  4.7K 5% CHIP  pkg 0201LF  page 320 : 1 = CLKREQ_RT_CPU1_P0_N ; 2 = GND
R1388  Q_RES  1K 1% EMPTY  pkg 0201LF  page 320 : 1 = P1V8_CPU1_RT_1D ; 2 = RXDET_BYP_RT_CPU1_P0
R1389  Q_RES  10K 1% CHIP  pkg 0201LF  page 320 : 1 = RXDET_BYP_RT_CPU1_P0 ; 2 = GND
R1390  Q_RES  4.7K 5% CHIP  pkg 0201LF  page 185 : 1 = P1V8_CPU1_RT_1D ; 2 = SMB_RT_CPU1_P0_ROM_MUX_2D_R_SCL
R1391  Q_RES  1K 1% CHIP  pkg 0201LF  page 287 : 1 = JTAG_TRST_RT_CPU0_P1_N ; 2 = GND
R1392  Q_RES  4.7K 5% CHIP  pkg 0201LF  page 287 : 1 = JTAG_TCK_RT_CPU0_P1 ; 2 = GND
R1393  Q_RES  4.7K 5% CHIP  pkg 0201LF  page 185 : 1 = P1V8_CPU1_RT_1D ; 2 = SMB_RT_CPU1_P1_ROM_MUX_2D_R_SDA
R1394  Q_RES  4.7K 5% CHIP  pkg 0201LF  page 185 : 1 = P1V8_CPU1_RT_1D ; 2 = SMB_RT_CPU1_P1_ROM_MUX_2D_R_SCL
R1395  Q_RES  4.7K 5% CHIP  pkg 0201LF  page 287 : 1 = CLKREQ_RT_CPU0_P1_N ; 2 = GND
R1396  Q_RES  10K 1% CHIP  pkg 0402LF  page 144 : 1 = FM_M2_SSD_0_PEDET ; 2 = P3V3_AUX
R1397  Q_RES  1K 1% EMPTY  pkg 0201LF  page 287 : 1 = P1V8_CPU0_RT_1D ; 2 = RXDET_BYP_RT_CPU0_P1
R1398  Q_RES  10K 1% CHIP  pkg 0201LF  page 287 : 1 = RXDET_BYP_RT_CPU0_P1 ; 2 = GND
R1399  Q_RES  4.7K 5% CHIP  pkg 0201LF  page 185 : 1 = P1V8_CPU1_RT_1D ; 2 = SMB_RT_CPU1_P3_ROM_MUX_2D_R_SDA
R1400  Q_RES  1K 1% CHIP  pkg 0201LF  page 298 : 1 = JTAG_TRST_RT_CPU0_P2_N ; 2 = GND
R1401  Q_RES  4.7K 5% CHIP  pkg 0201LF  page 298 : 1 = JTAG_TCK_RT_CPU0_P2 ; 2 = GND
R1402  Q_RES  4.7K 5% CHIP  pkg 0201LF  page 185 : 1 = P1V8_CPU1_RT_1D ; 2 = SMB_RT_CPU1_P3_ROM_MUX_2D_R_SCL
R1403  Q_RES  4.7K 5% CHIP  pkg 0201LF  page 185 : 1 = P1V8_CPU1_RT_1D ; 2 = SMB_RT_CPU1_P2_ROM_MUX_2D_R_SDA
R1404  Q_RES  4.7K 5% CHIP  pkg 0201LF  page 298 : 1 = CLKREQ_RT_CPU0_P2_N ; 2 = GND
R1405  Q_RES  1K 1% EMPTY  pkg 0201LF  page 298 : 1 = P1V8_CPU0_RT_1D ; 2 = RXDET_BYP_RT_CPU0_P2
R1406  Q_RES  10K 1% CHIP  pkg 0201LF  page 298 : 1 = RXDET_BYP_RT_CPU0_P2 ; 2 = GND
R1407  Q_RES  4.7K 5% CHIP  pkg 0201LF  page 185 : 1 = P1V8_CPU1_RT_1D ; 2 = SMB_RT_CPU1_P2_ROM_MUX_2D_R_SCL
R1408  Q_RES  1K 1% CHIP  pkg 0201LF  page 309 : 1 = JTAG_TRST_RT_CPU0_P3_N ; 2 = GND
R1409  Q_RES  4.7K 5% CHIP  pkg 0201LF  page 309 : 1 = JTAG_TCK_RT_CPU0_P3 ; 2 = GND
R1410  Q_RES  1K 1% CHIP  pkg 0201LF  page 185 : 1 = P1V8_CPU0_RT_1D ; 2 = SMB_RT_CPU0_P0_ROM_MUX_1D_SDA
R1411  Q_RES  1K 1% CHIP  pkg 0201LF  page 185 : 1 = P1V8_CPU0_RT_1D ; 2 = SMB_RT_CPU0_P0_ROM_MUX_1D_SCL
R1412  Q_RES  4.7K 5% CHIP  pkg 0201LF  page 309 : 1 = CLKREQ_RT_CPU0_P3_N ; 2 = GND
R1413  Q_RES  1K 1% EMPTY  pkg 0201LF  page 309 : 1 = P1V8_CPU0_RT_1D ; 2 = RXDET_BYP_RT_CPU0_P3
R1414  Q_RES  10K 1% CHIP  pkg 0201LF  page 309 : 1 = RXDET_BYP_RT_CPU0_P3 ; 2 = GND
R1415  Q_RES  1K 1% CHIP  pkg 0201LF  page 185 : 1 = P1V8_CPU0_RT_1D ; 2 = SMB_RT_CPU0_P1_ROM_MUX_1D_SDA
R1416  Q_RES  1K 1% CHIP  pkg 0201LF  page 342 : 1 = JTAG_TRST_RT_CPU1_P2_N ; 2 = GND
R1417  Q_RES  4.7K 5% CHIP  pkg 0201LF  page 342 : 1 = JTAG_TCK_RT_CPU1_P2 ; 2 = GND
R1418  Q_RES  1K 1% CHIP  pkg 0201LF  page 185 : 1 = P1V8_CPU0_RT_1D ; 2 = SMB_RT_CPU0_P1_ROM_MUX_1D_SCL
R1419  Q_RES  4.7K 5% CHIP  pkg 0402LF  page 164 : 1 = PVDD18_S5_P0 ; 2 = UART_LS_EN_R_N
R1420  Q_RES  1K 1% CHIP  pkg 0201LF  page 185 : 1 = P1V8_CPU0_RT_1D ; 2 = SMB_RT_CPU0_P3_ROM_MUX_1D_SDA
R1421  Q_RES  4.7K 5% CHIP  pkg 0201LF  page 342 : 1 = CLKREQ_RT_CPU1_P2_N ; 2 = GND
R1422  Q_RES  100 1% CHIP  pkg 0402LF  page 85 : 1 = PWRGD_CPU0_PWROK ; 2 = PWRGD_CPU1_PWROK
R1423  Q_RES  0 5% CHIP  pkg 0402LF  page 164 : 1 = UART_CPU0_SCM_UART1_RX ; 2 = UART_CPU0_SCM_UART1_R_RX
R1424  Q_RES  2.2K 5% CHIP  pkg 0402LF  page 55 : 1 = PVDD18_S5_P1 ; 2 = INT_CPU1_HP_UBM_N
R1425  Q_RES  0 5% CHIP  pkg 0402LF  page 164 : 1 = UART_CPU0_SCM_LVC3_UART1_R_TX ; 2 = UART_CPU0_SCM_LVC3_UART1_TX
R1426  Q_RES  1K 1% EMPTY  pkg 0201LF  page 342 : 1 = P1V8_CPU1_RT_1D ; 2 = RXDET_BYP_RT_CPU1_P2
R1427  Q_RES  10K 1% CHIP  pkg 0201LF  page 342 : 1 = RXDET_BYP_RT_CPU1_P2 ; 2 = GND
R1428  Q_RES  1K 1% CHIP  pkg 0201LF  page 185 : 1 = P1V8_CPU0_RT_1D ; 2 = SMB_RT_CPU0_P3_ROM_MUX_1D_SCL
R1429  Q_RES  1K 1% CHIP  pkg 0201LF  page 353 : 1 = JTAG_TRST_RT_CPU1_P3_N ; 2 = GND
R1430  Q_RES  4.7K 5% CHIP  pkg 0201LF  page 353 : 1 = JTAG_TCK_RT_CPU1_P3 ; 2 = GND
R1431  Q_RES  1K 1% CHIP  pkg 0201LF  page 185 : 1 = P1V8_CPU0_RT_1D ; 2 = SMB_RT_CPU0_P2_ROM_MUX_1D_SDA
R1432  Q_RES  1K 1% CHIP  pkg 0201LF  page 185 : 1 = P1V8_CPU0_RT_1D ; 2 = SMB_RT_CPU0_P2_ROM_MUX_1D_SCL
R1433  Q_RES  4.7K 5% CHIP  pkg 0201LF  page 353 : 1 = CLKREQ_RT_CPU1_P3_N ; 2 = GND
R1434  Q_RES  1K 1% EMPTY  pkg 0201LF  page 353 : 1 = P1V8_CPU1_RT_1D ; 2 = RXDET_BYP_RT_CPU1_P3
R1435  Q_RES  10K 1% CHIP  pkg 0201LF  page 353 : 1 = RXDET_BYP_RT_CPU1_P3 ; 2 = GND
R1436  Q_RES  1K 1% CHIP  pkg 0201LF  page 185 : 1 = P1V8_CPU1_RT_1D ; 2 = SMB_RT_CPU1_P0_ROM_MUX_1D_SDA
R1437  Q_RES  1K 1% CHIP  pkg 0201LF  page 185 : 1 = P1V8_CPU1_RT_1D ; 2 = SMB_RT_CPU1_P0_ROM_MUX_1D_SCL
R1438  Q_RES  4.7K 5% EMPTY  pkg 0201LF  page 276 : 1 = P1V8_CPU0_RT_1D ; 2 = JTAG_TDI_RT_CPU0_P0
R1439  Q_RES  4.7K 5% EMPTY  pkg 0201LF  page 276 : 1 = P1V8_CPU0_RT_1D ; 2 = JTAG_TMS_RT_CPU0_P0
R1440  Q_RES  100K 1% CHIP  pkg 0402LF  page 259 : 1 = P12V_MEM_CPU1 ; 2 = PWRGD_P12V_MEM_CPU1_EN
R1441  Q_RES  16.9K 1% CHIP  pkg 0402LF  page 259 : 1 = PWRGD_P12V_MEM_CPU1_EN ; 2 = GND
R1442  Q_RES  100K 1% CHIP  pkg 0402LF  page 259 : 1 = P12V_MEM_CPU0 ; 2 = PWRGD_P12V_MEM_CPU0_EN
R1443  Q_RES  16.9K 1% CHIP  pkg 0402LF  page 259 : 1 = PWRGD_P12V_MEM_CPU0_EN ; 2 = GND
R1444  Q_RES  130 1% CHIP  pkg 0402LF  page 165 : 1 = P3V3_AUX ; 2 = LED_BIOS_DBG_MODE_R
R1445  Q_RES  1K 1% EMPTY  pkg 0201LF  page 276 : 1 = P1V8_CPU0_RT_1D ; 2 = JTAG_TDO_RT_CPU0_P0
R1446  Q_RES  4.7K 5% EMPTY  pkg 0201LF  page 276 : 1 = P1V8_CPU0_RT_1D ; 2 = JTAG_TCK_RT_CPU0_P0
R1447  Q_RES  0 5% CHIP  pkg 0402LF  page 151 : 1 = SMB_CPU_5_SCL ; 2 = SMB_CPU_5_R1_SCL
R1448  Q_RES  1K 1% CHIP  pkg 0201LF  page 185 : 1 = P1V8_CPU1_RT_1D ; 2 = SMB_RT_CPU1_P1_ROM_MUX_1D_SDA
R1449  Q_RES  10K 5% CHIP  pkg 0402LF  page 259 : 1 = P3V3_AUX ; 2 = PWRGD_P12V_MEM_CPU1_EN_N
R1450  Q_RES  10K 5% CHIP  pkg 0402LF  page 259 : 1 = P3V3_AUX ; 2 = PWRGD_P12V_MEM_CPU0_EN_N
R1451  Q_RES  1K 1% CHIP  pkg 0201LF  page 185 : 1 = P1V8_CPU1_RT_1D ; 2 = SMB_RT_CPU1_P1_ROM_MUX_1D_SCL
R1452  Q_RES  10K 5% CHIP  pkg 0402LF  page 259 : 1 = P1V8_AUX ; 2 = PWRGD_P12V_MEM_CPU1
R1453  Q_RES  0 5% CHIP  pkg 0402LF  page 151 : 1 = SMB_CPU_5_SDA ; 2 = SMB_CPU_5_R1_SDA
R1454  Q_RES  4.7K 5% EMPTY  pkg 0201LF  page 331 : 1 = P1V8_CPU1_RT_1D ; 2 = JTAG_TDI_RT_CPU1_P1
R1455  Q_RES  4.7K 5% EMPTY  pkg 0201LF  page 331 : 1 = P1V8_CPU1_RT_1D ; 2 = JTAG_TMS_RT_CPU1_P1
R1456  Q_RES  1K 1% EMPTY  pkg 0201LF  page 331 : 1 = P1V8_CPU1_RT_1D ; 2 = JTAG_TDO_RT_CPU1_P1
R1457  Q_RES  10K 5% CHIP  pkg 0402LF  page 259 : 1 = P1V8_AUX ; 2 = PWRGD_P12V_MEM_CPU0
R1458  Q_RES  33 5% CHIP  pkg 0402LF  page 259 : 1 = PWRGD_P12V_MEM_CPU0 ; 2 = PWRGD_P12V_MEM_CPU0_R
R1459  Q_RES  33 5% CHIP  pkg 0402LF  page 259 : 1 = PWRGD_P12V_MEM_CPU1 ; 2 = PWRGD_P12V_MEM_CPU1_R
R1460  Q_RES  2.2K 5% EMPTY  pkg 0402LF  page 151 : 1 = I3C_BMC_SWB_SDA ; 2 = P3V3_AUX
R1461  Q_RES  4.7K 5% EMPTY  pkg 0201LF  page 331 : 1 = P1V8_CPU1_RT_1D ; 2 = JTAG_TCK_RT_CPU1_P1
R1462  Q_RES  1K 1% CHIP  pkg 0201LF  page 185 : 1 = P1V8_CPU1_RT_1D ; 2 = SMB_RT_CPU1_P3_ROM_MUX_1D_SDA
R1463  Q_RES  1K 1% CHIP  pkg 0201LF  page 185 : 1 = P1V8_CPU1_RT_1D ; 2 = SMB_RT_CPU1_P3_ROM_MUX_1D_SCL
R1464  Q_RES  4.7K 5% EMPTY  pkg 0201LF  page 320 : 1 = P1V8_CPU1_RT_1D ; 2 = JTAG_TDI_RT_CPU1_P0
R1465  Q_RES  4.7K 5% EMPTY  pkg 0201LF  page 320 : 1 = P1V8_CPU1_RT_1D ; 2 = JTAG_TMS_RT_CPU1_P0
R1466  Q_RES  1K 1% EMPTY  pkg 0201LF  page 320 : 1 = P1V8_CPU1_RT_1D ; 2 = JTAG_TDO_RT_CPU1_P0
R1467  Q_RES  4.7K 5% EMPTY  pkg 0201LF  page 320 : 1 = P1V8_CPU1_RT_1D ; 2 = JTAG_TCK_RT_CPU1_P0
R1468  Q_RES  1K 1% CHIP  pkg 0201LF  page 185 : 1 = P1V8_CPU1_RT_1D ; 2 = SMB_RT_CPU1_P2_ROM_MUX_1D_SDA
R1469  Q_RES  1K 1% CHIP  pkg 0201LF  page 185 : 1 = P1V8_CPU1_RT_1D ; 2 = SMB_RT_CPU1_P2_ROM_MUX_1D_SCL
R1470  Q_RES  4.7K 5% EMPTY  pkg 0201LF  page 287 : 1 = P1V8_CPU0_RT_1D ; 2 = JTAG_TDI_RT_CPU0_P1
R1471  Q_RES  4.7K 5% EMPTY  pkg 0201LF  page 287 : 1 = P1V8_CPU0_RT_1D ; 2 = JTAG_TMS_RT_CPU0_P1
R1472  Q_RES  1K 1% EMPTY  pkg 0201LF  page 287 : 1 = P1V8_CPU0_RT_1D ; 2 = JTAG_TDO_RT_CPU0_P1
R1473  Q_RES  4.7K 5% EMPTY  pkg 0201LF  page 287 : 1 = P1V8_CPU0_RT_1D ; 2 = JTAG_TCK_RT_CPU0_P1
R1474  Q_RES  10K 1% EMPTY  pkg 0402LF  page 169 : 1 = P12V_AUX_DSC_G2 ; 2 = GND
R1475  Q_RES  10K 1% EMPTY  pkg 0402LF  page 169 : 1 = P3V3_AUX_DSC_G2 ; 2 = GND
R1476  Q_RES  4.7K 5% EMPTY  pkg 0201LF  page 298 : 1 = P1V8_CPU0_RT_1D ; 2 = JTAG_TDI_RT_CPU0_P2
R1477  Q_RES  4.7K 5% EMPTY  pkg 0201LF  page 298 : 1 = P1V8_CPU0_RT_1D ; 2 = JTAG_TMS_RT_CPU0_P2
R1478  Q_RES  1K 1% EMPTY  pkg 0201LF  page 298 : 1 = P1V8_CPU0_RT_1D ; 2 = JTAG_TDO_RT_CPU0_P2
R1479  Q_RES  4.7K 5% EMPTY  pkg 0201LF  page 298 : 1 = P1V8_CPU0_RT_1D ; 2 = JTAG_TCK_RT_CPU0_P2
R1480  Q_RES  10 1% EMPTY  pkg 2512LF  page 169 : 1 = P12V_AUX ; 2 = P12V_AUX_DSC
R1481  Q_RES  10 1% EMPTY  pkg 2512LF  page 169 : 1 = P3V3_AUX ; 2 = P3V3_AUX_DSC
R1482  Q_RES  4.7K 5% EMPTY  pkg 0201LF  page 309 : 1 = P1V8_CPU0_RT_1D ; 2 = JTAG_TDI_RT_CPU0_P3
R1483  Q_RES  4.7K 5% EMPTY  pkg 0201LF  page 309 : 1 = P1V8_CPU0_RT_1D ; 2 = JTAG_TMS_RT_CPU0_P3
R1484  Q_RES  1K 1% EMPTY  pkg 0201LF  page 309 : 1 = P1V8_CPU0_RT_1D ; 2 = JTAG_TDO_RT_CPU0_P3
R1485  Q_RES  4.7K 5% EMPTY  pkg 0201LF  page 309 : 1 = P1V8_CPU0_RT_1D ; 2 = JTAG_TCK_RT_CPU0_P3
R1486  Q_RES  0 5% CHIP  pkg 0402LF  page 134 : 1 = P12V_OCP_SFF_BUF_EN_R ; 2 = P3V3_OCP_EN_1_R
R1487  Q_RES  0 5% CHIP  pkg 0402LF  page 135 : 1 = P12V_OCP_SFF_BUF_EN_R ; 2 = P3V3_OCP_EN_1_R2
R1488  Q_RES  4.7K 5% EMPTY  pkg 0201LF  page 342 : 1 = P1V8_CPU1_RT_1D ; 2 = JTAG_TDI_RT_CPU1_P2
R1489  Q_RES  4.7K 5% EMPTY  pkg 0201LF  page 342 : 1 = P1V8_CPU1_RT_1D ; 2 = JTAG_TMS_RT_CPU1_P2
R1490  Q_RES  1K 1% EMPTY  pkg 0201LF  page 342 : 1 = P1V8_CPU1_RT_1D ; 2 = JTAG_TDO_RT_CPU1_P2
R1491  Q_RES  10K 5% EMPTY  pkg 0402LF  page 188 : 1 = P3V3 ; 2 = PWRGD_P3V3_EN_R
R1492  Q_RES  10K 5% CHIP  pkg 0402LF  page 188 : 1 = P3V3_AUX ; 2 = PWRGD_P3V3_EN_N
R1493  Q_RES  10K 5% CHIP  pkg 0402LF  page 188 : 1 = P1V8_AUX ; 2 = PWRGD_P3V3_R1
R1494  Q_RES  33 5% CHIP  pkg 0402LF  page 151 : 1 = SMB_VR_3V3STBY_SDA ; 2 = SMB_SCM_2_R1_SDA
R1495  Q_RES  33 5% CHIP  pkg 0402LF  page 151 : 1 = SMB_SCM_2_R1_SCL ; 2 = SMB_SCM_2_R2_SCL
R1496  Q_RES  33 5% CHIP  pkg 0402LF  page 151 : 1 = SMB_SCM_2_R1_SDA ; 2 = SMB_SCM_2_R2_SDA
R1497  Q_RES  33 5% CHIP  pkg 0402LF  page 151 : 1 = SMB_VR_3V3AUX_SCL ; 2 = SMB_SCM_2_R3_SCL
R1498  Q_RES  33 5% CHIP  pkg 0402LF  page 151 : 1 = SMB_VR_3V3AUX_SDA ; 2 = SMB_SCM_2_R3_SDA
R1499  Q_RES  4.7K 5% EMPTY  pkg 0201LF  page 342 : 1 = P1V8_CPU1_RT_1D ; 2 = JTAG_TCK_RT_CPU1_P2
R1500  Q_RES  0 5% CHIP  pkg 0402LF  page 247 : 1 = HP_LVC3_OCP_V3_1_R_EN ; 2 = P12V_OCP_SFF_BUF_EN_R
R1501  Q_RES  10K 5% EMPTY  pkg 0402LF  page 76 : 1 = PVDD18_S5_P1 ; 2 = CLK_CPU1_RTCCLK
R1502  Q_RES  10K 5% CHIP  pkg 0402LF  page 76 : 1 = GND ; 2 = CLK_CPU1_RTCCLK
R1503  Q_RES  30K 1% CHIP  pkg 0402LF  page 29 : 1 = PVDD18_S5_P0 ; 2 = ESPI_CPU0_D0
R1504  Q_RES  30K 1% CHIP  pkg 0402LF  page 29 : 1 = PVDD18_S5_P0 ; 2 = ESPI_CPU0_D1
R1505  Q_RES  30K 1% CHIP  pkg 0402LF  page 29 : 1 = PVDD18_S5_P0 ; 2 = ESPI_CPU0_D2
R1506  Q_RES  30K 1% CHIP  pkg 0402LF  page 29 : 1 = PVDD18_S5_P0 ; 2 = ESPI_CPU0_D3
R1507  Q_RES  1K 1% CHIP  pkg 0402LF  page 165 : 1 = P3V3_AUX ; 2 = LED_BIOS_DBG_MODE_N
R1508  Q_RES  100 1% CHIP  pkg 0402LF  page 167 : 1 = GND ; 2 = PD_BIOS_DEBUG_MODE
